(kicad_pcb
	(version 20260206)
	(generator "pcbnew")
	(generator_version "10.0")
	(general
		(thickness 1.6)
		(legacy_teardrops no)
	)
	(paper "A4")
	(title_block
		(title "12092022_DA0F0TMDCD0_F0T_Management_Board_D_brd_V3_OCP.brd")
		(comment 1 "Grand Teton / footprints 330-335 of 1440")
	)
	(layers
		(0 "F.Cu" signal "TOP")
		(4 "In1.Cu" signal "GND")
		(6 "In2.Cu" signal "IN1")
		(8 "In3.Cu" signal "GND1")
		(10 "In4.Cu" signal "IN2")
		(12 "In5.Cu" signal "VCC")
		(14 "In6.Cu" signal "VCC1")
		(16 "In7.Cu" signal "IN3")
		(18 "In8.Cu" signal "GND2")
		(20 "In9.Cu" signal "IN4")
		(22 "In10.Cu" signal "GND3")
		(2 "B.Cu" signal "BOTTOM")
		(9 "F.Adhes" user "F.Adhesive")
		(11 "B.Adhes" user "B.Adhesive")
		(13 "F.Paste" user "Package Geometry/Pastemask Top")
		(15 "B.Paste" user "Package Geometry/Pastemask Bottom")
		(5 "F.SilkS" user "Ref Des/Silkscreen Top")
		(7 "B.SilkS" user "Ref Des/Silkscreen Bottom")
		(1 "F.Mask" user "Board Geometry/Soldermask Top")
		(3 "B.Mask" user "Board Geometry/Soldermask Bottom")
		(17 "Dwgs.User" user "User.Drawings")
		(19 "Cmts.User" user "User.Comments")
		(21 "Eco1.User" user "User.Eco1")
		(23 "Eco2.User" user "User.Eco2")
		(25 "Edge.Cuts" user "Board Geometry/Outline")
		(27 "Margin" user)
		(31 "F.CrtYd" user "Package Geometry/Place Bound Top")
		(29 "B.CrtYd" user "Package Geometry/Place Bound Bottom")
		(35 "F.Fab" user "Ref Des/Assembly Top")
		(33 "B.Fab" user "Ref Des/Assembly Bottom")
	)
	(footprint ""
		(layer "F.Cu")
		(at 11.557 -9.652)
		(property "Reference" "R768"
			(at 0 0 0)
			(layer "F.SilkS")
			(hide yes)
			(effects
				(font
					(size 1.27 1.27)
				)
			)
		)
		(property "Value" ""
			(at 0 0 0)
			(layer "F.Fab")
			(effects
				(font
					(size 1.27 1.27)
				)
			)
		)
		(duplicate_pad_numbers_are_jumpers no)
		(fp_line
			(start -0.7874 -0.4064)
			(end 0.7874 -0.4064)
			(stroke
				(width 0.1524)
				(type default)
			)
			(layer "F.SilkS")
		)
		(fp_line
			(start -0.7874 0.4064)
			(end -0.7874 -0.4064)
			(stroke
				(width 0.1524)
				(type default)
			)
			(layer "F.SilkS")
		)
		(fp_line
			(start 0.7874 -0.4064)
			(end 0.7874 0.4064)
			(stroke
				(width 0.1524)
				(type default)
			)
			(layer "F.SilkS")
		)
		(fp_line
			(start 0.7874 0.4064)
			(end -0.7874 0.4064)
			(stroke
				(width 0.1524)
				(type default)
			)
			(layer "F.SilkS")
		)
		(fp_line
			(start -0.67945 -0.305054)
			(end -0.12065 -0.305054)
			(stroke
				(width 0.1)
				(type default)
			)
			(layer "F.Fab")
		)
		(fp_line
			(start -0.67945 0.3048)
			(end -0.67945 -0.305054)
			(stroke
				(width 0.1)
				(type default)
			)
			(layer "F.Fab")
		)
		(fp_line
			(start -0.12065 -0.305054)
			(end -0.12065 -0.2794)
			(stroke
				(width 0.1)
				(type default)
			)
			(layer "F.Fab")
		)
		(fp_line
			(start -0.12065 -0.2794)
			(end 0.12065 -0.2794)
			(stroke
				(width 0.1)
				(type default)
			)
			(layer "F.Fab")
		)
		(fp_line
			(start -0.12065 0.2794)
			(end -0.12065 0.3048)
			(stroke
				(width 0.1)
				(type default)
			)
			(layer "F.Fab")
		)
		(fp_line
			(start -0.12065 0.3048)
			(end -0.67945 0.3048)
			(stroke
				(width 0.1)
				(type default)
			)
			(layer "F.Fab")
		)
		(fp_line
			(start 0.120396 0.2794)
			(end -0.12065 0.2794)
			(stroke
				(width 0.1)
				(type default)
			)
			(layer "F.Fab")
		)
		(fp_line
			(start 0.120396 0.3048)
			(end 0.120396 0.2794)
			(stroke
				(width 0.1)
				(type default)
			)
			(layer "F.Fab")
		)
		(fp_line
			(start 0.12065 -0.3048)
			(end 0.67945 -0.3048)
			(stroke
				(width 0.1)
				(type default)
			)
			(layer "F.Fab")
		)
		(fp_line
			(start 0.12065 -0.2794)
			(end 0.12065 -0.3048)
			(stroke
				(width 0.1)
				(type default)
			)
			(layer "F.Fab")
		)
		(fp_line
			(start 0.67945 -0.3048)
			(end 0.67945 0.3048)
			(stroke
				(width 0.1)
				(type default)
			)
			(layer "F.Fab")
		)
		(fp_line
			(start 0.67945 0.3048)
			(end 0.120396 0.3048)
			(stroke
				(width 0.1)
				(type default)
			)
			(layer "F.Fab")
		)
		(pad "1" smd circle
			(at -0.40005 0)
			(size 0 0)
			(layers "F.Cu" "F.Mask" "F.Paste")
			(net "P3V3_AUX")
		)
		(pad "2" smd circle
			(at 0.40005 0)
			(size 0 0)
			(layers "F.Cu" "F.Mask" "F.Paste")
			(net "REAR_PWR_BTN_N")
		)
	)
	(footprint ""
		(layer "F.Cu")
		(at 37.690298 -38.53561 -90)
		(property "Reference" "R155"
			(at 0 0 270)
			(layer "F.SilkS")
			(hide yes)
			(effects
				(font
					(size 1.27 1.27)
				)
			)
		)
		(property "Value" ""
			(at 0 0 270)
			(layer "F.Fab")
			(effects
				(font
					(size 1.27 1.27)
				)
			)
		)
		(duplicate_pad_numbers_are_jumpers no)
		(fp_line
			(start -0.7874 0.4064)
			(end -0.7874 -0.4064)
			(stroke
				(width 0.1524)
				(type default)
			)
			(layer "F.SilkS")
		)
		(fp_line
			(start 0.7874 0.4064)
			(end -0.7874 0.4064)
			(stroke
				(width 0.1524)
				(type default)
			)
			(layer "F.SilkS")
		)
		(fp_line
			(start -0.7874 -0.4064)
			(end 0.7874 -0.4064)
			(stroke
				(width 0.1524)
				(type default)
			)
			(layer "F.SilkS")
		)
		(fp_line
			(start 0.7874 -0.4064)
			(end 0.7874 0.4064)
			(stroke
				(width 0.1524)
				(type default)
			)
			(layer "F.SilkS")
		)
		(fp_line
			(start -0.67945 0.3048)
			(end -0.67945 -0.305054)
			(stroke
				(width 0.1)
				(type default)
			)
			(layer "F.Fab")
		)
		(fp_line
			(start -0.12065 0.3048)
			(end -0.67945 0.3048)
			(stroke
				(width 0.1)
				(type default)
			)
			(layer "F.Fab")
		)
		(fp_line
			(start 0.120396 0.3048)
			(end 0.120396 0.2794)
			(stroke
				(width 0.1)
				(type default)
			)
			(layer "F.Fab")
		)
		(fp_line
			(start 0.67945 0.3048)
			(end 0.120396 0.3048)
			(stroke
				(width 0.1)
				(type default)
			)
			(layer "F.Fab")
		)
		(fp_line
			(start -0.12065 0.2794)
			(end -0.12065 0.3048)
			(stroke
				(width 0.1)
				(type default)
			)
			(layer "F.Fab")
		)
		(fp_line
			(start 0.120396 0.2794)
			(end -0.12065 0.2794)
			(stroke
				(width 0.1)
				(type default)
			)
			(layer "F.Fab")
		)
		(fp_line
			(start -0.12065 -0.2794)
			(end 0.12065 -0.2794)
			(stroke
				(width 0.1)
				(type default)
			)
			(layer "F.Fab")
		)
		(fp_line
			(start 0.12065 -0.2794)
			(end 0.12065 -0.3048)
			(stroke
				(width 0.1)
				(type default)
			)
			(layer "F.Fab")
		)
		(fp_line
			(start 0.12065 -0.3048)
			(end 0.67945 -0.3048)
			(stroke
				(width 0.1)
				(type default)
			)
			(layer "F.Fab")
		)
		(fp_line
			(start 0.67945 -0.3048)
			(end 0.67945 0.3048)
			(stroke
				(width 0.1)
				(type default)
			)
			(layer "F.Fab")
		)
		(fp_line
			(start -0.67945 -0.305054)
			(end -0.12065 -0.305054)
			(stroke
				(width 0.1)
				(type default)
			)
			(layer "F.Fab")
		)
		(fp_line
			(start -0.12065 -0.305054)
			(end -0.12065 -0.2794)
			(stroke
				(width 0.1)
				(type default)
			)
			(layer "F.Fab")
		)
		(pad "1" smd circle
			(at -0.40005 0 270)
			(size 0 0)
			(layers "F.Cu" "F.Mask" "F.Paste")
			(net "P3V3_AUX")
		)
		(pad "2" smd circle
			(at 0.40005 0 270)
			(size 0 0)
			(layers "F.Cu" "F.Mask" "F.Paste")
			(net "P3V3_P2V5_P1V8_RVDD")
		)
	)
	(footprint ""
		(layer "F.Cu")
		(at 11.27125 -64.54394 -90)
		(property "Reference" "PR530"
			(at 0 0 270)
			(layer "F.SilkS")
			(hide yes)
			(effects
				(font
					(size 1.27 1.27)
				)
			)
		)
		(property "Value" ""
			(at 0 0 270)
			(layer "F.Fab")
			(effects
				(font
					(size 1.27 1.27)
				)
			)
		)
		(duplicate_pad_numbers_are_jumpers no)
		(fp_line
			(start -0.7874 0.4064)
			(end -0.7874 -0.4064)
			(stroke
				(width 0.1524)
				(type default)
			)
			(layer "F.SilkS")
		)
		(fp_line
			(start 0.7874 0.4064)
			(end -0.7874 0.4064)
			(stroke
				(width 0.1524)
				(type default)
			)
			(layer "F.SilkS")
		)
		(fp_line
			(start -0.7874 -0.4064)
			(end 0.7874 -0.4064)
			(stroke
				(width 0.1524)
				(type default)
			)
			(layer "F.SilkS")
		)
		(fp_line
			(start 0.7874 -0.4064)
			(end 0.7874 0.4064)
			(stroke
				(width 0.1524)
				(type default)
			)
			(layer "F.SilkS")
		)
		(fp_line
			(start -0.67945 0.3048)
			(end -0.67945 -0.305054)
			(stroke
				(width 0.1)
				(type default)
			)
			(layer "F.Fab")
		)
		(fp_line
			(start -0.12065 0.3048)
			(end -0.67945 0.3048)
			(stroke
				(width 0.1)
				(type default)
			)
			(layer "F.Fab")
		)
		(fp_line
			(start 0.120396 0.3048)
			(end 0.120396 0.2794)
			(stroke
				(width 0.1)
				(type default)
			)
			(layer "F.Fab")
		)
		(fp_line
			(start 0.67945 0.3048)
			(end 0.120396 0.3048)
			(stroke
				(width 0.1)
				(type default)
			)
			(layer "F.Fab")
		)
		(fp_line
			(start -0.12065 0.2794)
			(end -0.12065 0.3048)
			(stroke
				(width 0.1)
				(type default)
			)
			(layer "F.Fab")
		)
		(fp_line
			(start 0.120396 0.2794)
			(end -0.12065 0.2794)
			(stroke
				(width 0.1)
				(type default)
			)
			(layer "F.Fab")
		)
		(fp_line
			(start -0.12065 -0.2794)
			(end 0.12065 -0.2794)
			(stroke
				(width 0.1)
				(type default)
			)
			(layer "F.Fab")
		)
		(fp_line
			(start 0.12065 -0.2794)
			(end 0.12065 -0.3048)
			(stroke
				(width 0.1)
				(type default)
			)
			(layer "F.Fab")
		)
		(fp_line
			(start 0.12065 -0.3048)
			(end 0.67945 -0.3048)
			(stroke
				(width 0.1)
				(type default)
			)
			(layer "F.Fab")
		)
		(fp_line
			(start 0.67945 -0.3048)
			(end 0.67945 0.3048)
			(stroke
				(width 0.1)
				(type default)
			)
			(layer "F.Fab")
		)
		(fp_line
			(start -0.67945 -0.305054)
			(end -0.12065 -0.305054)
			(stroke
				(width 0.1)
				(type default)
			)
			(layer "F.Fab")
		)
		(fp_line
			(start -0.12065 -0.305054)
			(end -0.12065 -0.2794)
			(stroke
				(width 0.1)
				(type default)
			)
			(layer "F.Fab")
		)
		(pad "1" smd circle
			(at -0.40005 0 270)
			(size 0 0)
			(layers "F.Cu" "F.Mask" "F.Paste")
			(net "GND")
		)
		(pad "2" smd circle
			(at 0.40005 0 270)
			(size 0 0)
			(layers "F.Cu" "F.Mask" "F.Paste")
			(net "P3V3_AUX_FB_RC")
		)
	)
	(footprint ""
		(layer "F.Cu")
		(at 64.600328 -29.377132 -90)
		(property "Reference" "R217"
			(at 0 0 270)
			(layer "F.SilkS")
			(hide yes)
			(effects
				(font
					(size 1.27 1.27)
				)
			)
		)
		(property "Value" ""
			(at 0 0 270)
			(layer "F.Fab")
			(effects
				(font
					(size 1.27 1.27)
				)
			)
		)
		(duplicate_pad_numbers_are_jumpers no)
		(fp_line
			(start -0.7874 0.4064)
			(end -0.7874 -0.167132)
			(stroke
				(width 0.1524)
				(type default)
			)
			(layer "F.SilkS")
		)
		(fp_line
			(start 0.7874 0.4064)
			(end -0.7874 0.4064)
			(stroke
				(width 0.1524)
				(type default)
			)
			(layer "F.SilkS")
		)
		(fp_line
			(start 0.7874 -0.062992)
			(end 0.7874 0.4064)
			(stroke
				(width 0.1524)
				(type default)
			)
			(layer "F.SilkS")
		)
		(fp_line
			(start -0.397002 -0.4064)
			(end 0.277368 -0.4064)
			(stroke
				(width 0.1524)
				(type default)
			)
			(layer "F.SilkS")
		)
		(fp_line
			(start -0.67945 0.3048)
			(end -0.67945 -0.305054)
			(stroke
				(width 0.1)
				(type default)
			)
			(layer "F.Fab")
		)
		(fp_line
			(start -0.12065 0.3048)
			(end -0.67945 0.3048)
			(stroke
				(width 0.1)
				(type default)
			)
			(layer "F.Fab")
		)
		(fp_line
			(start 0.120396 0.3048)
			(end 0.120396 0.2794)
			(stroke
				(width 0.1)
				(type default)
			)
			(layer "F.Fab")
		)
		(fp_line
			(start 0.67945 0.3048)
			(end 0.120396 0.3048)
			(stroke
				(width 0.1)
				(type default)
			)
			(layer "F.Fab")
		)
		(fp_line
			(start -0.12065 0.2794)
			(end -0.12065 0.3048)
			(stroke
				(width 0.1)
				(type default)
			)
			(layer "F.Fab")
		)
		(fp_line
			(start 0.120396 0.2794)
			(end -0.12065 0.2794)
			(stroke
				(width 0.1)
				(type default)
			)
			(layer "F.Fab")
		)
		(fp_line
			(start -0.12065 -0.2794)
			(end 0.12065 -0.2794)
			(stroke
				(width 0.1)
				(type default)
			)
			(layer "F.Fab")
		)
		(fp_line
			(start 0.12065 -0.2794)
			(end 0.12065 -0.3048)
			(stroke
				(width 0.1)
				(type default)
			)
			(layer "F.Fab")
		)
		(fp_line
			(start 0.12065 -0.3048)
			(end 0.67945 -0.3048)
			(stroke
				(width 0.1)
				(type default)
			)
			(layer "F.Fab")
		)
		(fp_line
			(start 0.67945 -0.3048)
			(end 0.67945 0.3048)
			(stroke
				(width 0.1)
				(type default)
			)
			(layer "F.Fab")
		)
		(fp_line
			(start -0.67945 -0.305054)
			(end -0.12065 -0.305054)
			(stroke
				(width 0.1)
				(type default)
			)
			(layer "F.Fab")
		)
		(fp_line
			(start -0.12065 -0.305054)
			(end -0.12065 -0.2794)
			(stroke
				(width 0.1)
				(type default)
			)
			(layer "F.Fab")
		)
		(pad "1" smd circle
			(at -0.40005 0 270)
			(size 0 0)
			(layers "F.Cu" "F.Mask" "F.Paste")
			(net "USB_HOST_BMC_A_R_DP")
		)
		(pad "2" smd circle
			(at 0.40005 0 270)
			(size 0 0)
			(layers "F.Cu" "F.Mask" "F.Paste")
			(net "USB_HOST_BMC_A_DP")
		)
	)
	(footprint ""
		(layer "F.Cu")
		(at 18.415 -66.04 90)
		(property "Reference" "C20"
			(at 0 0 90)
			(layer "F.SilkS")
			(hide yes)
			(effects
				(font
					(size 1.27 1.27)
				)
			)
		)
		(property "Value" ""
			(at 0 0 90)
			(layer "F.Fab")
			(effects
				(font
					(size 1.27 1.27)
				)
			)
		)
		(duplicate_pad_numbers_are_jumpers no)
		(fp_line
			(start 0.7874 -0.4064)
			(end 0.7874 0.4064)
			(stroke
				(width 0.1524)
				(type default)
			)
			(layer "F.SilkS")
		)
		(fp_line
			(start -0.7874 -0.4064)
			(end 0.7874 -0.4064)
			(stroke
				(width 0.1524)
				(type default)
			)
			(layer "F.SilkS")
		)
		(fp_line
			(start 0.7874 0.4064)
			(end -0.7874 0.4064)
			(stroke
				(width 0.1524)
				(type default)
			)
			(layer "F.SilkS")
		)
		(fp_line
			(start -0.7874 0.4064)
			(end -0.7874 -0.4064)
			(stroke
				(width 0.1524)
				(type default)
			)
			(layer "F.SilkS")
		)
		(fp_line
			(start -0.12065 -0.305054)
			(end -0.12065 -0.2794)
			(stroke
				(width 0.1)
				(type default)
			)
			(layer "F.Fab")
		)
		(fp_line
			(start -0.67945 -0.305054)
			(end -0.12065 -0.305054)
			(stroke
				(width 0.1)
				(type default)
			)
			(layer "F.Fab")
		)
		(fp_line
			(start 0.67945 -0.3048)
			(end 0.67945 0.3048)
			(stroke
				(width 0.1)
				(type default)
			)
			(layer "F.Fab")
		)
		(fp_line
			(start 0.12065 -0.3048)
			(end 0.67945 -0.3048)
			(stroke
				(width 0.1)
				(type default)
			)
			(layer "F.Fab")
		)
		(fp_line
			(start 0.12065 -0.2794)
			(end 0.12065 -0.3048)
			(stroke
				(width 0.1)
				(type default)
			)
			(layer "F.Fab")
		)
		(fp_line
			(start -0.12065 -0.2794)
			(end 0.12065 -0.2794)
			(stroke
				(width 0.1)
				(type default)
			)
			(layer "F.Fab")
		)
		(fp_line
			(start 0.120396 0.2794)
			(end -0.12065 0.2794)
			(stroke
				(width 0.1)
				(type default)
			)
			(layer "F.Fab")
		)
		(fp_line
			(start -0.12065 0.2794)
			(end -0.12065 0.3048)
			(stroke
				(width 0.1)
				(type default)
			)
			(layer "F.Fab")
		)
		(fp_line
			(start 0.67945 0.3048)
			(end 0.120396 0.3048)
			(stroke
				(width 0.1)
				(type default)
			)
			(layer "F.Fab")
		)
		(fp_line
			(start 0.120396 0.3048)
			(end 0.120396 0.2794)
			(stroke
				(width 0.1)
				(type default)
			)
			(layer "F.Fab")
		)
		(fp_line
			(start -0.12065 0.3048)
			(end -0.67945 0.3048)
			(stroke
				(width 0.1)
				(type default)
			)
			(layer "F.Fab")
		)
		(fp_line
			(start -0.67945 0.3048)
			(end -0.67945 -0.305054)
			(stroke
				(width 0.1)
				(type default)
			)
			(layer "F.Fab")
		)
		(pad "1" smd circle
			(at -0.40005 0 90)
			(size 0 0)
			(layers "F.Cu" "F.Mask" "F.Paste")
			(net "P3V3_AUX")
		)
		(pad "2" smd circle
			(at 0.40005 0 90)
			(size 0 0)
			(layers "F.Cu" "F.Mask" "F.Paste")
			(net "GND")
		)
	)
	(footprint ""
		(layer "F.Cu")
		(at 39.73322 -36.571174 90)
		(property "Reference" "R154"
			(at 0 0 90)
			(layer "F.SilkS")
			(hide yes)
			(effects
				(font
					(size 1.27 1.27)
				)
			)
		)
		(property "Value" ""
			(at 0 0 90)
			(layer "F.Fab")
			(effects
				(font
					(size 1.27 1.27)
				)
			)
		)
		(duplicate_pad_numbers_are_jumpers no)
		(fp_line
			(start 0.7874 -0.4064)
			(end 0.7874 0.4064)
			(stroke
				(width 0.1524)
				(type default)
			)
			(layer "F.SilkS")
		)
		(fp_line
			(start -0.7874 -0.4064)
			(end 0.7874 -0.4064)
			(stroke
				(width 0.1524)
				(type default)
			)
			(layer "F.SilkS")
		)
		(fp_line
			(start 0.7874 0.4064)
			(end -0.7874 0.4064)
			(stroke
				(width 0.1524)
				(type default)
			)
			(layer "F.SilkS")
		)
		(fp_line
			(start -0.7874 0.4064)
			(end -0.7874 -0.4064)
			(stroke
				(width 0.1524)
				(type default)
			)
			(layer "F.SilkS")
		)
		(fp_line
			(start -0.12065 -0.305054)
			(end -0.12065 -0.2794)
			(stroke
				(width 0.1)
				(type default)
			)
			(layer "F.Fab")
		)
		(fp_line
			(start -0.67945 -0.305054)
			(end -0.12065 -0.305054)
			(stroke
				(width 0.1)
				(type default)
			)
			(layer "F.Fab")
		)
		(fp_line
			(start 0.67945 -0.3048)
			(end 0.67945 0.3048)
			(stroke
				(width 0.1)
				(type default)
			)
			(layer "F.Fab")
		)
		(fp_line
			(start 0.12065 -0.3048)
			(end 0.67945 -0.3048)
			(stroke
				(width 0.1)
				(type default)
			)
			(layer "F.Fab")
		)
		(fp_line
			(start 0.12065 -0.2794)
			(end 0.12065 -0.3048)
			(stroke
				(width 0.1)
				(type default)
			)
			(layer "F.Fab")
		)
		(fp_line
			(start -0.12065 -0.2794)
			(end 0.12065 -0.2794)
			(stroke
				(width 0.1)
				(type default)
			)
			(layer "F.Fab")
		)
		(fp_line
			(start 0.120396 0.2794)
			(end -0.12065 0.2794)
			(stroke
				(width 0.1)
				(type default)
			)
			(layer "F.Fab")
		)
		(fp_line
			(start -0.12065 0.2794)
			(end -0.12065 0.3048)
			(stroke
				(width 0.1)
				(type default)
			)
			(layer "F.Fab")
		)
		(fp_line
			(start 0.67945 0.3048)
			(end 0.120396 0.3048)
			(stroke
				(width 0.1)
				(type default)
			)
			(layer "F.Fab")
		)
		(fp_line
			(start 0.120396 0.3048)
			(end 0.120396 0.2794)
			(stroke
				(width 0.1)
				(type default)
			)
			(layer "F.Fab")
		)
		(fp_line
			(start -0.12065 0.3048)
			(end -0.67945 0.3048)
			(stroke
				(width 0.1)
				(type default)
			)
			(layer "F.Fab")
		)
		(fp_line
			(start -0.67945 0.3048)
			(end -0.67945 -0.305054)
			(stroke
				(width 0.1)
				(type default)
			)
			(layer "F.Fab")
		)
		(pad "1" smd circle
			(at -0.40005 0 90)
			(size 0 0)
			(layers "F.Cu" "F.Mask" "F.Paste")
			(net "P1V8_AUX")
		)
		(pad "2" smd circle
			(at 0.40005 0 90)
			(size 0 0)
			(layers "F.Cu" "F.Mask" "F.Paste")
			(net "P3V3_P2V5_P1V8_RVDD")
		)
	)
)
